FILE_TYPE = CONNECTIVITY;
{Allegro Design Entry HDL 17.2-2016 S081 (4005846) 1/11/2022}
"PAGE_NUMBER" = 44;
0"NC";
1"GND\g";
2"CLK_25M_NSSC_CPU1_DP";
3"PD_CPU1_TXT_PLTEN";
4"PU_CPU1_TXT_AGENT";
5"JTAG_DBP_CPU1_QS_GTL_R_TMS";
6"JTAG_CPU1_MUX_GTL_TDO";
7"JTAG_DBP_CPU1_GTL_R_TDI";
8"JTAG_DBP_CPU1_GTL_R_TCK";
9"PU_CPU1_SOCKET_ID0";
10"PU_CPU1_SOCKET_ID1";
11"PU_CPU1_SOCKET_ID2";
12"PU_CPU1_SAFE_MODE_BOOT";
13"CPU1_RSVD<85>";
14"CPU1_RSVD<82>";
15"PD_EXT_CLK_SEL_CPU1";
16"CPU1_RSVD<157>";
17"PUD_XTAL_CPU1_MODE1";
18"FM_CPU1_PROC_ID0";
19"FM_CPU1_PROC_ID1";
20"PD_CPU1_PROCDIS_COD_GTL_N";
21"H_CPU1_PREQ_QS_GTL_R_N";
22"H_CPU1_PRDY_QS_GTL_R_N";
23"FM_CPU1_PKGID0";
24"FM_CPU1_PKGID1";
25"FM_CPU1_PKGID2";
26"PECI_CPU1_GTL_R";
27"TP_CPU1_BR23";
28"PU_CPU1_LEGACY_SKT";
29"PU_CPU1_FRMAGENT";
30"PD_CPU1_DMIMODE_OVERRIDE";
31"RST_CPU1_DRAM_GH_N";
32"RST_CPU1_DRAM_EF_N";
33"I3C_SPD_DDREFGH_CPU1_SDA";
34"I3C_SPD_DDREFGH_CPU1_SCL";
35"RST_CPU1_DRAM_CD_N";
36"RST_CPU1_DRAM_AB_N";
37"I3C_SPD_DDRABCD_CPU1_SDA";
38"I3C_SPD_DDRABCD_CPU1_SCL";
39"H_CPU1_BMCINIT_LVC1";
40"PD_CPU1_BIST_ENABLE";
41"CLK_100M_DB2000_CPU1_BCLK3_DP";
42"CLK_100M_DB2000_CPU1_BCLK3_DN";
43"CLK_100M_DB2000_CPU1_BCLK2_DP";
44"CLK_100M_DB2000_CPU1_BCLK2_DN";
45"CLK_100M_DB2000_CPU1_BCLK0_DP";
46"CLK_100M_DB2000_CPU1_BCLK1_DN";
47"CLK_100M_DB2000_CPU1_BCLK1_DP";
48"CLK_100M_DB2000_CPU1_BCLK0_DN";
49"PUD_XTAL_CPU1_MODE0";
50"CPU1_RSVD<153>";
51"CLK_25M_NSSC_CPU1_DN";
52"PD_CPU1_PROCDIS_COD_GTL_N";
53"PECI_CPU_GTL";
54"JTAG_MUX_CPU1_GTL_TDI";
55"H_CPU_PRDY_QS_GTL_N";
56"H_CPU_PREQ_QS_GTL_N";
57"JTAG_DBP_CPU_GTL_TCK";
58"JTAG_DBP_CPU_QS_GTL_TMS";
%"Q_RES"
"1","(-7325,6375)","0","pure_quanta","I10";
;
PART_NUMBER"CS03322FB03"
WATTAGE"1/16W"
MATERIAL"CHIP"
TOLERANCE"1%"
PACK_TYPE"0402LF"
VALUE"33.2"
$LOCATION"R63"
CDS_LIB"pure_quanta"
$LOCATION"R63"
CDS_LOCATION"R63"
$SEC"1"
CDS_SEC"1";
"B"
$PN"2"26;
"A"
$PN"1"53;
%"Q_RES"
"1","(-7325,6475)","0","pure_quanta","I11";
;
PART_NUMBER"CS11002FB07"
VALUE"100"
TOLERANCE"1%"
PACK_TYPE"0402LF"
MATERIAL"CHIP"
WATTAGE"1/16W"
$LOCATION"R62"
CDS_LIB"pure_quanta"
$LOCATION"R62"
CDS_LOCATION"R62"
$SEC"1"
CDS_SEC"1";
"B"
$PN"2"21;
"A"
$PN"1"56;
%"Q_RES"
"1","(-7325,6525)","0","pure_quanta","I16";
;
PART_NUMBER"CS01002FB07"
VALUE"10"
TOLERANCE"1%"
MATERIAL"CHIP"
WATTAGE"1/16W"
PACK_TYPE"0402LF"
$LOCATION"R61"
CDS_LIB"pure_quanta"
$LOCATION"R61"
CDS_LOCATION"R61"
$SEC"1"
CDS_SEC"1";
"B"
$PN"2"22;
"A"
$PN"1"55;
%"SOCKET4677_AZIF0045P001C01CS"
"1","(-4500,7100)","0","pure_quanta","I51";
;
PART_NUMBER"DGA^7000023"
VALUE"SOCKET4677_AZIF0045-P001C01CS"
PART_TYPE"SMLF"
MATERIAL"IO"
$LOCATION"U1"
CDS_LMAN_SYM_OUTLINE"-1100,1100,1050,-1050"
NEEDS_NO_SIZE"TRUE"
CDS_LIB"pure_quanta"
CDS_LOCATION"U1"
$SEC"1"
CDS_SEC"1";
"XTAL_CLK_DN \B"
$PN"CW31"51;
"RSVD157"
$PN"D4"50;
"RSVD120"
$PN"CL72"49;
"BCLK0_DN \B"
$PN"AT30"48;
"BCLK1_DP"
$PN"CW29"47;
"BCLK1_DN \B"
$PN"CY28"46;
"BCLK0_DP"
$PN"AV30"45;
"BCLK2_DN \B"
$PN"AU29"44;
"BCLK2_DP"
$PN"AV28"43;
"BCLK3_DN \B"
$PN"CW27"42;
"BCLK3_DP"
$PN"DA27"41;
"BIST_ENABLE"
$PN"AT18"40;
"BMCINIT"
$PN"BN23"39;
"DDR0123_SPDSCL"
$PN"BT22"38;
"DDR0123_SPDSDA"
$PN"BY22"37;
"DDR01_RESET_N \B"
$PN"AU50"36;
"DDR23_RESET_N \B"
$PN"AV51"35;
"DDR4567_SPDSCL"
$PN"CU17"34;
"DDR4567_SPDSDA"
$PN"CT18"33;
"DDR45_RESET_N \B"
$PN"CY42"32;
"DDR67_RESET_N \B"
$PN"CY55"31;
"DMIMODE_OVERRIDE"
$PN"AW17"30;
"FRMAGENT"
$PN"AU17"29;
"LEGACY_SKT"
$PN"CY59"28;
"RSVD72"
$PN"BR23"27;
"PECI"
$PN"BH24"26;
"PKG_ID2"
$PN"BN64"25;
"PKG_ID1"
$PN"AY63"24;
"PKG_ID0"
$PN"BL64"23;
"PRDY_N \B"
$PN"BP26"22;
"PREQ_N \B"
$PN"AV22"21;
"PROCDIS_N \B"
$PN"DA52"20;
"PROC_ID1"
$PN"BH71"19;
"PROC_ID0"
$PN"BG72"18;
"RSVD108"
$PN"CJ72"17;
"RSVD161"
$PN"G5"16;
"RSVD76"
$PN"BY24"15;
"RSVD88"
$PN"CD71"14;
"RSVD91"
$PN"CE70"13;
"SAFE_MODE_BOOT"
$PN"AU23"12;
"SOCKET_ID2"
$PN"CT61"11;
"SOCKET_ID1"
$PN"CY61"10;
"SOCKET_ID0"
$PN"CW60"9;
"TCK"
$PN"BT24"8;
"TDI"
$PN"BV24"7;
"TDO"
$PN"BW25"6;
"TMS"
$PN"BR25"5;
"TXT_AGENT"
$PN"BT26"4;
"TXT_PLTEN"
$PN"CT20"3;
"XTAL_CLK_DP"
$PN"CY32"2;
%"Q_RES"
"2","(-1575,5275)","0","pure_quanta","I55";
;
PART_NUMBER"CS12402FB01"
PACK_TYPE"0402LF"
VALUE"240"
TOLERANCE"1%"
WATTAGE"1/16W"
MATERIAL"EMPTY"
$LOCATION"R1270"
CDS_LIB"pure_quanta"
CDS_LOCATION"R1270"
$SEC"1"
CDS_SEC"1";
"A"
$PN"1"52;
"B"
$PN"2"1;
%"UNIVERSAL_GND"
"1","(-1575,5000)","0","logical_power","I56";
;
CDS_LIB"logical_power"
HDL_POWER"GND";
"A"1;
%"Q_RES"
"1","(-7325,6175)","0","pure_quanta","I7";
;
PART_NUMBER"CS11002FB07"
VALUE"100"
TOLERANCE"1%"
MATERIAL"CHIP"
WATTAGE"1/16W"
PACK_TYPE"0402LF"
$LOCATION"R66"
CDS_LIB"pure_quanta"
$LOCATION"R66"
CDS_LOCATION"R66"
$SEC"1"
CDS_SEC"1";
"B"
$PN"2"5;
"A"
$PN"1"58;
%"Q_RES"
"1","(-7325,6225)","0","pure_quanta","I8";
;
PART_NUMBER"CS11002FB07"
VALUE"100"
TOLERANCE"1%"
PACK_TYPE"0402LF"
$LOCATION"R65"
CDS_LIB"pure_quanta"
MATERIAL"CHIP"
WATTAGE"1/16W"
$LOCATION"R65"
CDS_LOCATION"R65"
$SEC"1"
CDS_SEC"1";
"B"
$PN"2"8;
"A"
$PN"1"57;
%"Q_RES"
"1","(-7325,6275)","0","pure_quanta","I9";
;
PART_NUMBER"CS12002FB06"
WATTAGE"1/16W"
PACK_TYPE"0402LF"
VALUE"200"
TOLERANCE"1%"
MATERIAL"CHIP"
$LOCATION"R64"
CDS_LIB"pure_quanta"
$LOCATION"R64"
CDS_LOCATION"R64"
$SEC"1"
CDS_SEC"1";
"B"
$PN"2"7;
"A"
$PN"1"54;
END.
